# ZAIUS-LV CARD-DVT-X01-BOM-X00_20170420_Final.xls.xlsx — Component Qual Tracker (bom)
|  |  |  |  |  |  |  |  | Part to be included on following build: |  |  |  |  |  |
| Item No. | Part Group | Single/Sole/Multi | Item Description | ODM P/N | Customer PN | Vendor | Vendor P/N | X00 Build | X01 Build | X02 Build | Qual Build | Qualification Target Date | Qualification Complete Date |
|  | VR Controllers |  |  |  |  | Vendor #1 |  |  |  |  |  |  |  |
|  |  |  |  |  |  | Vendor #2 |  |  |  |  |  |  |  |
|  | FETS |  |  |  |  | Vendor #1 |  |  |  |  |  |  |  |
|  |  |  |  |  |  | Vendor #2 |  |  |  |  |  |  |  |
|  | INDUCTORS |  |  |  |  | Vendor #1 |  |  |  |  |  |  |  |
|  |  |  |  |  |  | Vendor #2 |  |  |  |  |  |  |  |
|  | VREG CAPS |  |  |  |  | Vendor #1 |  |  |  |  |  |  |  |
|  |  |  |  |  |  | Vendor #2 |  |  |  |  |  |  |  |
|  | CRYSTALS |  |  |  |  | Vendor #1 |  |  |  |  |  |  |  |
|  |  |  |  |  |  | Vendor #2 |  |  |  |  |  |  |  |
|  | CONNECTORS |  |  |  |  | Vendor #1 |  |  |  |  |  |  |  |
|  |  |  |  |  |  | Vendor #2 |  |  |  |  |  |  |  |
|  | IC'S |  |  |  |  | Vendor #1 |  |  |  |  |  |  |  |
|  |  |  |  |  |  | Vendor #2 |  |  |  |  |  |  |  |
|  | MISC. |  |  |  |  | Vendor #1 |  |  |  |  |  |  |  |
|  | (HEATSINKS) |  |  |  |  | Vendor #2 |  |  |  |  |  |  |  |
